# BASEBOARD_FAB2 (Tioga Pass) — schematic netlist excerpt (pin names and nets, part order shuffled) for the footprints in the layout excerpt that follows; sources: Cadence DE-HDL packaged netlist, KiCad conversion of Wiwynn_Tioga_Pass_MB.brd

C5G116  CAP  47UF 4V 20% X6S  pkg 0805  page 243 : A = PVDDQ_KLM ; B = GND
R1W39  RES  0.0 5% CHIP  pkg 0402  page 176 : A = SMB_DEBUG_STBY_LVC3_SDA_CONN ; B = SMB_DEBUG_STBY_LVC3_SDA_R1
C7P20  CAP  100UF 4V 20% X5R  pkg 0805  page 225 : A = PVDDQ_GHJ ; B = GND

(kicad_pcb
	(version 20260206)
	(generator "pcbnew")
	(generator_version "10.0")
	(general
		(thickness 1.6)
		(legacy_teardrops no)
	)
	(paper "A4")
	(title_block
		(title "Wiwynn_Tioga_Pass_MB.brd")
		(comment 1 "Tioga Pass / footprints 3875-3877 of 4770")
	)
	(layers
		(0 "F.Cu" signal "TOP")
		(4 "In1.Cu" signal "L2GND")
		(6 "In2.Cu" signal "L3")
		(8 "In3.Cu" signal "L4GND")
		(10 "In4.Cu" signal "L5")
		(12 "In5.Cu" signal "L6GND")
		(14 "In6.Cu" signal "L7VCC")
		(16 "In7.Cu" signal "L8VCC")
		(18 "In8.Cu" signal "L9GND")
		(20 "In9.Cu" signal "L10")
		(22 "In10.Cu" signal "L11GND")
		(24 "In11.Cu" signal "L12")
		(26 "In12.Cu" signal "L13GND")
		(2 "B.Cu" signal "BOTTOM")
		(9 "F.Adhes" user "F.Adhesive")
		(11 "B.Adhes" user "B.Adhesive")
		(13 "F.Paste" user "Package Geometry/Pastemask Top")
		(15 "B.Paste" user "Package Geometry/Pastemask Bottom")
		(5 "F.SilkS" user "Ref Des/Silkscreen Top")
		(7 "B.SilkS" user "Ref Des/Silkscreen Bottom")
		(1 "F.Mask" user "Board Geometry/Soldermask Top")
		(3 "B.Mask" user "Board Geometry/Soldermask Bottom")
		(17 "Dwgs.User" user "User.Drawings")
		(19 "Cmts.User" user "User.Comments")
		(21 "Eco1.User" user "User.Eco1")
		(23 "Eco2.User" user "User.Eco2")
		(25 "Edge.Cuts" user "Board Geometry/Outline")
		(27 "Margin" user)
		(31 "F.CrtYd" user "Package Geometry/Place Bound Top")
		(29 "B.CrtYd" user "Package Geometry/Place Bound Bottom")
		(35 "F.Fab" user "Ref Des/Assembly Top")
		(33 "B.Fab" user "Ref Des/Assembly Bottom")
	)
	(footprint ""
		(layer "B.Cu")
		(at 108.432854 -68.17614 180)
		(property "Reference" "C7P20"
			(at 0 0 0)
			(layer "B.SilkS")
			(hide yes)
			(effects
				(font
					(size 1.27 1.27)
				)
				(justify mirror)
			)
		)
		(property "Value" ""
			(at 0 0 0)
			(layer "B.Fab")
			(effects
				(font
					(size 1.27 1.27)
				)
				(justify mirror)
			)
		)
		(duplicate_pad_numbers_are_jumpers no)
		(fp_poly
			(pts
				(xy 0.7239 -0.2159) (xy -0.7239 -0.2159) (xy -0.7239 1.9939) (xy 0.7239 1.9939)
			)
			(stroke
				(width 0)
				(type default)
			)
			(fill no)
			(layer "B.CrtYd")
		)
		(fp_line
			(start 0.7239 1.9939)
			(end -0.7239 1.9939)
			(stroke
				(width 0.1)
				(type default)
			)
			(layer "B.Fab")
		)
		(fp_line
			(start 0.7239 -0.2159)
			(end 0.7239 1.9939)
			(stroke
				(width 0.1)
				(type default)
			)
			(layer "B.Fab")
		)
		(fp_line
			(start -0.7239 1.9939)
			(end -0.7239 -0.2159)
			(stroke
				(width 0.1)
				(type default)
			)
			(layer "B.Fab")
		)
		(fp_line
			(start -0.7239 -0.2159)
			(end 0.7239 -0.2159)
			(stroke
				(width 0.1)
				(type default)
			)
			(layer "B.Fab")
		)
		(pad "1" smd rect
			(at 0 0)
			(size 1.27 1.016)
			(layers "B.Cu" "B.Mask" "B.Paste")
			(net "PVDDQ_GHJ")
		)
		(pad "2" smd rect
			(at 0 1.778)
			(size 1.27 1.016)
			(layers "B.Cu" "B.Mask" "B.Paste")
			(net "GND")
		)
		(zone
			(layer "B.Cu")
			(hatch none 0.5)
			(connect_pads
				(clearance 0)
			)
			(min_thickness 0.25)
			(keepout
				(tracks not_allowed)
				(vias allowed)
				(pads allowed)
				(copperpour not_allowed)
				(footprints allowed)
			)
			(placement
				(enabled no)
				(sheetname "")
			)
			(fill
				(thermal_gap 0.5)
				(thermal_bridge_width 0.5)
				(island_removal_mode 0)
			)
			(polygon
				(pts
					(xy 107.797854 -68.68414) (xy 109.067854 -68.68414) (xy 109.067854 -69.44614) (xy 107.797854 -69.44614)
				)
			)
		)
	)
	(footprint ""
		(layer "B.Cu")
		(at 477.848422 -132.838444)
		(property "Reference" "R1W39"
			(at 0.8382 -0.67818 0)
			(unlocked yes)
			(layer "B.SilkS")
			(effects
				(font
					(size 0.4064 0.254)
					(thickness 0.1524)
				)
				(justify left mirror)
			)
		)
		(property "Value" ""
			(at 0 0 0)
			(layer "B.Fab")
			(effects
				(font
					(size 1.27 1.27)
				)
				(justify mirror)
			)
		)
		(duplicate_pad_numbers_are_jumpers no)
		(fp_poly
			(pts
				(xy 0.2794 -0.1016) (xy -0.2794 -0.1016) (xy -0.2794 0.9906) (xy 0.2794 0.9906)
			)
			(stroke
				(width 0)
				(type default)
			)
			(fill no)
			(layer "B.CrtYd")
		)
		(fp_line
			(start -0.2794 -0.1016)
			(end 0.2794 -0.1016)
			(stroke
				(width 0.1)
				(type default)
			)
			(layer "B.Fab")
		)
		(fp_line
			(start -0.2794 0.9906)
			(end -0.2794 -0.1016)
			(stroke
				(width 0.1)
				(type default)
			)
			(layer "B.Fab")
		)
		(fp_line
			(start 0.2794 -0.1016)
			(end 0.2794 0.9906)
			(stroke
				(width 0.1)
				(type default)
			)
			(layer "B.Fab")
		)
		(fp_line
			(start 0.2794 0.9906)
			(end -0.2794 0.9906)
			(stroke
				(width 0.1)
				(type default)
			)
			(layer "B.Fab")
		)
		(pad "1" smd rect
			(at 0 0 180)
			(size 0.508 0.508)
			(layers "B.Cu" "B.Mask" "B.Paste")
			(net "SMB_DEBUG_STBY_LVC3_SDA_CONN")
		)
		(pad "2" smd rect
			(at 0 0.889 180)
			(size 0.508 0.508)
			(layers "B.Cu" "B.Mask" "B.Paste")
			(net "SMB_DEBUG_STBY_LVC3_SDA_R1")
		)
		(zone
			(layer "B.Cu")
			(hatch none 0.5)
			(connect_pads
				(clearance 0)
			)
			(min_thickness 0.25)
			(keepout
				(tracks allowed)
				(vias not_allowed)
				(pads allowed)
				(copperpour not_allowed)
				(footprints allowed)
			)
			(placement
				(enabled no)
				(sheetname "")
			)
			(fill
				(thermal_gap 0.5)
				(thermal_bridge_width 0.5)
				(island_removal_mode 0)
			)
			(polygon
				(pts
					(xy 478.102422 -132.584444) (xy 477.594422 -132.584444) (xy 477.594422 -132.203444) (xy 478.102422 -132.203444)
				)
			)
		)
		(zone
			(layer "B.Cu")
			(hatch none 0.5)
			(connect_pads
				(clearance 0)
			)
			(min_thickness 0.25)
			(keepout
				(tracks not_allowed)
				(vias allowed)
				(pads allowed)
				(copperpour not_allowed)
				(footprints allowed)
			)
			(placement
				(enabled no)
				(sheetname "")
			)
			(fill
				(thermal_gap 0.5)
				(thermal_bridge_width 0.5)
				(island_removal_mode 0)
			)
			(polygon
				(pts
					(xy 478.102422 -132.203444) (xy 477.594422 -132.203444) (xy 477.594422 -132.584444) (xy 478.102422 -132.584444)
				)
			)
		)
	)
	(footprint ""
		(layer "B.Cu")
		(at 94.06636 -149.7711 90)
		(property "Reference" "C5G116"
			(at -1.64973 0.78994 180)
			(unlocked yes)
			(layer "B.SilkS")
			(effects
				(font
					(size 0.7874 0.5842)
					(thickness 0.1524)
				)
				(justify mirror)
			)
		)
		(property "Value" ""
			(at 0 0 90)
			(layer "B.Fab")
			(effects
				(font
					(size 1.27 1.27)
				)
				(justify mirror)
			)
		)
		(duplicate_pad_numbers_are_jumpers no)
		(fp_rect
			(start -0.7239 -0.2159)
			(end 0.7239 1.9939)
			(stroke
				(width 0)
				(type default)
			)
			(fill no)
			(layer "B.CrtYd")
		)
		(fp_line
			(start 0.7239 -0.2159)
			(end 0.7239 1.9939)
			(stroke
				(width 0.1)
				(type default)
			)
			(layer "B.Fab")
		)
		(fp_line
			(start -0.7239 -0.2159)
			(end 0.7239 -0.2159)
			(stroke
				(width 0.1)
				(type default)
			)
			(layer "B.Fab")
		)
		(fp_line
			(start 0.7239 1.9939)
			(end -0.7239 1.9939)
			(stroke
				(width 0.1)
				(type default)
			)
			(layer "B.Fab")
		)
		(fp_line
			(start -0.7239 1.9939)
			(end -0.7239 -0.2159)
			(stroke
				(width 0.1)
				(type default)
			)
			(layer "B.Fab")
		)
		(pad "1" smd rect
			(at 0 0 270)
			(size 1.27 1.016)
			(layers "B.Cu" "B.Mask" "B.Paste")
			(net "PVDDQ_KLM")
		)
		(pad "2" smd rect
			(at 0 1.778 270)
			(size 1.27 1.016)
			(layers "B.Cu" "B.Mask" "B.Paste")
			(net "GND")
		)
		(zone
			(layer "B.Cu")
			(hatch none 0.5)
			(connect_pads
				(clearance 0)
			)
			(min_thickness 0.25)
			(keepout
				(tracks not_allowed)
				(vias allowed)
				(pads allowed)
				(copperpour not_allowed)
				(footprints allowed)
			)
			(placement
				(enabled no)
				(sheetname "")
			)
			(fill
				(thermal_gap 0.5)
				(thermal_bridge_width 0.5)
				(island_removal_mode 0)
			)
			(polygon
				(pts
					(xy 94.57436 -149.1361) (xy 95.33636 -149.1361) (xy 95.33636 -150.4061) (xy 94.57436 -150.4061)
				)
			)
		)
	)
)
